FILE_TYPE = MULTI_PHYS_TABLE;

PART 'BAS70057F'

{========================================================================================}
:VALUE          | PART_TYPE | MATERIAL | PART_NUMBER       = STANDARD        | LIFECYCLE      | PART_NUMBER       | JEDEC_TYPE    | DESCRIPTION                                | MANUFTR | MANUF_PN       | RD_CMPLS_LVL | CMPLS_LVL | CLASS | DIP_SMD | FP_ECN           | FROM_PJ  | DATA                     | EE_CHECK_LIST | STATUS | PSL | PREFERENCE | CREATOR | CREATEDAY  ;
{========================================================================================}
 'BAS70-05-7-F' | 'SMLF'    | 'IC'     | 'BC0BAS70Z01'(!)  = 'End of Design' | 'Comp-Approve' | 'BC0BAS70Z01'     |'SOT23_123XB'| 'DIODE SMD BAS70-05-7-F(70V,SHTKY,SOT-23)' | 'DDS'   | 'BAS70-05-7-F' | 'EP(V1)'     | 'EP(V1)'  | 'IC'  | ''      | ''               | 'S1D-OZ' | 'DDS_BAS70-04-05-06.pdf' | ''            | ''     | ''  | ''         | ''      | '20121220'
 'BAS70-05-7-F' | 'SMLF'    | 'EMPTY'  | 'BC0BAS70Z01'(!)  = 'End of Design' | 'Comp-Approve' | 'BC0BAS70Z01'     |'SOT23_123XB'| 'DIODE SMD BAS70-05-7-F(70V,SHTKY,SOT-23)' | 'DDS'   | 'BAS70-05-7-F' | 'EP(V1)'     | 'EP(V1)'  | 'IC'  | ''      | ''               | 'S1D-OZ' | 'DDS_BAS70-04-05-06.pdf' | ''            | ''     | ''  | ''         | ''      | '20121220'
 'BAS70-05-7-F' | 'SMLF'    | 'IC'     | 'BC0BAS70Z01SEL1'(!) = ''              | ''               | 'BC0BAS70Z01SEL1' |'SOT23_123XB'| 'DIODE SMD BAS70-05(70V,SHTKY,SOT-23)SELA' | 'DDS'   | 'BAS70-05-7-F' | 'EP(V1)'     | 'EP(V1)'  | 'IC'  | ''      | 'SEL_15QPN.xlsx' | 'S1D-OZ' | 'DDS_BAS70-04-05-06.pdf' | ''            | ''     | ''  | ''         | ''      | '20230705'
 'BAS70-05-7-F' | 'SMLF'    | 'EMPTY'  | 'BC0BAS70Z01SEL1'(!) = ''              | ''               | 'BC0BAS70Z01SEL1' |'SOT23_123XB'| 'DIODE SMD BAS70-05(70V,SHTKY,SOT-23)SELA' | 'DDS'   | 'BAS70-05-7-F' | 'EP(V1)'     | 'EP(V1)'  | 'IC'  | ''      | 'SEL_15QPN.xlsx' | 'S1D-OZ' | 'DDS_BAS70-04-05-06.pdf' | ''            | ''     | ''  | ''         | ''      | '20230705'

END_PART

END.

